(
  (version 16.5)
  (tool
    (creator "conceptHDL")
    (last "conceptHDL")
  )
  (library "mstr_symbols")
  (design "p3v3"
    (lastIds
      (lastNetId 4)
    )
    (nets
      ("N1" "g" -1 -1 1 3)
      ("N2" "page1_g" -1 -1 0 )
      ("N4" "page1_p3v3" -1 -1 0 )
      ("N3" "p3v3" -1 -1 2 )
    )

    (alias
      ("N2" -1 -1 "N1" -1 -1)
      ("N4" -1 -1 "N2" -1 -1)
      ("N4" -1 -1 "N3" -1 -1)
    )

  )
)
